FILE_TYPE = CONNECTIVITY;
{Allegro Design Entry HDL 16.6-p007 (v16-6-112F) 10/10/2012}
"PAGE_NUMBER" = 217;
0"NC";
1"PVDDQ_ABC\g";
2"GND\g";
3"VR_FET_SW_P12V_STBY_PVDDQ_ABC\g";
4"GND\g";
5"P12V_STBY\g";
6"GND\g";
7"PVDDQ_ABC\g";
8"PVDDQ_ABC\g";
9"GND\g";
10"PVDDQ_ABC\g";
11"GND\g";
12"PVDDQ_ABC\g";
13"GND\g";
14"PVDDQ_ABC\g";
15"GND\g";
16"PVDDQ_ABC\g";
17"GND\g";
18"PVDDQ_ABC\g";
19"GND\g";
20"GND\g";
21"PVDDQ_ABC\g";
22"GND\g";
23"PVDDQ_ABC\g";
24"PVDDQ_ABC\g";
25"GND\g";
26"PVDDQ_ABC\g";
27"GND\g";
28"VSENSE_PVDDQ_ABC_P";
29"VSENSE_PVDDQ_ABC_N";
%"PVDDQ_ABC"
"1","(2900,2000)","0","mstr_symbols","I109";
;
CDS_LIB"mstr_symbols"
VOLTAGE"1.2V"
BODY_TYPE"PLUMBING"
HDL_POWER"PVDDQ_ABC";
"G\NAC"1;
%"GND"
"1","(4625,1350)","0","mstr_symbols","I114";
;
ROOM"VDDQ_ABC_PWR_VR"
BOM_COST"MEM_VRD_PVDDQ_CD"
SIZE"1B"
CDS_LIB"mstr_symbols"
VOLTAGE"0"
BODY_TYPE"PLUMBING"
HDL_POWER"GND";
"A\NAC"2;
%"VCC_CORE"
"1","(200,1150)","0","mstr_symbols","I120";
;
HDL_POWER"VR_FET_SW_P12V_STBY_PVDDQ_ABC"
CDS_LIB"mstr_symbols";
"A"3;
%"GND"
"1","(200,475)","0","mstr_symbols","I123";
;
ROOM"VDDQ_ABC_PWR_VR"
BOM_COST"MEM_VRD_PVDDQ_CD"
SIZE"1B"
CDS_LIB"mstr_symbols"
VOLTAGE"0"
BODY_TYPE"PLUMBING"
HDL_POWER"GND";
"A\NAC"4;
%"CAPP"
"1","(200,700)","0","mstr_discrete","I175";
;
CDS_SEC"1"
MATERIAL"OSCON"
PACK_TYPE"2626"
VOLTAGE"16V"
LOCATION"C7G2"
TOLERANCE"20%"
VALUE"270UF"
PART_NUMBER"A31228-047"
CDS_LIB"mstr_discrete"
CDS_LOCATION"C7G2"
ROOM"VDDQ_ABC_PWR_VR"
SEC"1"
SEC_TYPE"2626";
"B"
$PN"2"4;
"A"
$PN"1"3;
%"P12V_STBY"
"1","(-550,1150)","0","mstr_symbols","I183";
;
VOLTAGE"12.0V"
CDS_LIB"mstr_symbols"
SIZE"1B"
BODY_TYPE"PLUMBING"
HDL_POWER"P12V_STBY";
"G\NAC"5;
%"GND"
"1","(150,2525)","0","mstr_symbols","I187";
;
ROOM"VDDQ_ABC_PWR_VR"
BOM_COST"MEM_VRD_PVDDQ_CD"
SIZE"1B"
CDS_LIB"mstr_symbols"
VOLTAGE"0"
BODY_TYPE"PLUMBING"
HDL_POWER"GND";
"A\NAC"6;
%"PVDDQ_ABC"
"1","(-1750,3125)","0","mstr_symbols","I192";
;
VOLTAGE"1.2V"
CDS_LIB"mstr_symbols"
BOM_COST"MEM_VRD_PVDDQ_CD"
ROOM"VDDQ_ABC_PWR_VR"
BODY_TYPE"PLUMBING"
HDL_POWER"PVDDQ_ABC";
"G\NAC"7;
%"PVDDQ_ABC"
"1","(2925,1275)","0","mstr_symbols","I201";
;
VOLTAGE"1.2V"
CDS_LIB"mstr_symbols"
BODY_TYPE"PLUMBING"
HDL_POWER"PVDDQ_ABC";
"G\NAC"8;
%"GND"
"1","(3575,625)","0","mstr_symbols","I203";
;
BOM_COST"MEM_VRD_PVDDQ_CD"
CDS_LIB"mstr_symbols"
VOLTAGE"0"
SIZE"1B"
BODY_TYPE"PLUMBING"
HDL_POWER"GND";
"A\NAC"9;
%"CAP_A"
"1","(2925,1000)","0","dev_discrete","I205";
;
LOCATION"C5F2"
VOLTAGE"4V"
VALUE"47UF"
TOLERANCE"20%"
MATERIAL"X5R"
PART_NUMBER"602433-106"
PACK_TYPE"0603V"
GROUP"PWR_MLCC_CAP"
BOM_SS"NOPOP"
CDS_LOCATION"C5F2"
CDS_SEC"1"
SEC_TYPE"0603V"
SEC"1"
CDS_LIB"dev_discrete";
"B"
$PN"2"9;
"A"
$PN"1"8;
%"CAP_A"
"1","(3275,1000)","0","dev_discrete","I206";
;
BOM_SS"NOPOP"
VOLTAGE"4V"
TOLERANCE"20%"
LOCATION"C5F1"
VALUE"47UF"
MATERIAL"X5R"
PACK_TYPE"0603V"
GROUP"PWR_MLCC_CAP"
PART_NUMBER"602433-106"
CDS_LIB"dev_discrete"
CDS_LOCATION"C5F1"
CDS_SEC"1"
SEC_TYPE"0603V"
SEC"1";
"B"
$PN"2"9;
"A"
$PN"1"8;
%"CAP_A"
"1","(3675,1000)","0","dev_discrete","I207";
;
VOLTAGE"4V"
TOLERANCE"20%"
MATERIAL"X5R"
VALUE"47UF"
PACK_TYPE"0603V"
LOCATION"C5G10"
BOM_SS"NOPOP"
GROUP"PWR_MLCC_CAP"
PART_NUMBER"602433-106"
CDS_LIB"dev_discrete"
CDS_LOCATION"C5G10"
CDS_SEC"1"
SEC_TYPE"0603V"
SEC"1";
"B"
$PN"2"9;
"A"
$PN"1"8;
%"CAP_A"
"1","(4000,1725)","0","dev_discrete","I208";
;
VOLTAGE"4V"
TOLERANCE"20%"
VALUE"47UF"
LOCATION"C5T2"
MATERIAL"X5R"
PART_NUMBER"602433-106"
PACK_TYPE"0603V"
BOM_SS"NOPOP"
GROUP"PWR_MLCC_CAP"
CDS_LIB"dev_discrete"
SEC"1"
SEC_TYPE"0603V"
CDS_SEC"1"
CDS_LOCATION"C5T2";
"B"
$PN"2"2;
"A"
$PN"1"1;
%"CAP_A"
"1","(4350,1725)","0","dev_discrete","I209";
;
PART_NUMBER"602433-106"
MATERIAL"X5R"
PACK_TYPE"0603V"
VALUE"47UF"
LOCATION"C5U11"
TOLERANCE"20%"
VOLTAGE"4V"
BOM_SS"NOPOP"
GROUP"PWR_MLCC_CAP"
CDS_LIB"dev_discrete"
CDS_LOCATION"C5U11"
CDS_SEC"1"
SEC_TYPE"0603V"
SEC"1";
"B"
$PN"2"2;
"A"
$PN"1"1;
%"CAP_A"
"1","(4750,1725)","0","dev_discrete","I210";
;
PART_NUMBER"602433-106"
MATERIAL"X5R"
VOLTAGE"4V"
VALUE"47UF"
LOCATION"C5T13"
BOM_SS"NOPOP"
GROUP"PWR_MLCC_CAP"
PACK_TYPE"0603V"
TOLERANCE"20%"
CDS_LIB"dev_discrete"
SEC"1"
SEC_TYPE"0603V"
CDS_SEC"1"
CDS_LOCATION"C5T13";
"B"
$PN"2"2;
"A"
$PN"1"1;
%"CAP_A"
"1","(3650,1725)","0","dev_discrete","I211";
;
MATERIAL"X5R"
PACK_TYPE"0603V"
PART_NUMBER"602433-106"
TOLERANCE"20%"
VOLTAGE"4V"
VALUE"47UF"
LOCATION"C5T4"
GROUP"PWR_MLCC_CAP"
BOM_SS"078.1061T.M001"
CDS_LIB"dev_discrete"
SEC"1"
SEC_TYPE"0603V"
CDS_SEC"1"
CDS_LOCATION"C5T4";
"B"
$PN"2"2;
"A"
$PN"1"1;
%"CAP_A"
"1","(3250,1725)","0","dev_discrete","I212";
;
TOLERANCE"20%"
MATERIAL"X5R"
PART_NUMBER"602433-106"
BOM_SS"NOPOP"
GROUP"PWR_MLCC_CAP"
VOLTAGE"4V"
PACK_TYPE"0603V"
LOCATION"C5T1"
VALUE"47UF"
CDS_LIB"dev_discrete"
SEC"1"
SEC_TYPE"0603V"
CDS_SEC"1"
CDS_LOCATION"C5T1";
"B"
$PN"2"2;
"A"
$PN"1"1;
%"CAP_A"
"1","(2900,1725)","0","dev_discrete","I213";
;
BOM_SS"NOPOP"
GROUP"PWR_MLCC_CAP"
PART_NUMBER"602433-106"
VALUE"47UF"
TOLERANCE"20%"
VOLTAGE"4V"
MATERIAL"X5R"
PACK_TYPE"0603V"
LOCATION"C5G19"
CDS_LIB"dev_discrete"
SEC"1"
SEC_TYPE"0603V"
CDS_SEC"1"
CDS_LOCATION"C5G19";
"B"
$PN"2"2;
"A"
$PN"1"1;
%"PVDDQ_ABC"
"1","(-900,3125)","0","mstr_symbols","I214";
;
BOM_COST"MEM_VRD_PVDDQ_CD"
CDS_LIB"mstr_symbols"
ROOM"VDDQ_ABC_PWR_VR"
VOLTAGE"1.2V"
BODY_TYPE"PLUMBING"
HDL_POWER"PVDDQ_ABC";
"G\NAC"10;
%"GND"
"1","(-1400,2500)","0","mstr_symbols","I215";
;
ROOM"VDDQ_ABC_PWR_VR"
BOM_COST"MEM_VRD_PVDDQ_CD"
SIZE"1B"
CDS_LIB"mstr_symbols"
VOLTAGE"0"
BODY_TYPE"PLUMBING"
HDL_POWER"GND";
"A\NAC"11;
%"PVDDQ_ABC"
"1","(-1825,300)","0","mstr_symbols","I242";
;
ROOM"VDDQ_ABC_PWR_VR"
CDS_LIB"mstr_symbols"
BOM_COST"PROC_SOCKET "
VOLTAGE"1.2V"
BODY_TYPE"PLUMBING"
HDL_POWER"PVDDQ_ABC";
"G\NAC"12;
%"GND"
"1","(-1825,-300)","0","mstr_symbols","I248";
;
BOM_COST"PROC_VRD_VCCIN_CPU0"
ROOM"VDDQ_ABC_PWR_VR"
CDS_LIB"mstr_symbols"
VOLTAGE"0"
SIZE"1B"
BODY_TYPE"PLUMBING"
HDL_POWER"GND";
"A\NAC"13;
%"PVDDQ_ABC"
"1","(-1825,-400)","0","mstr_symbols","I249";
;
ROOM"VDDQ_ABC_PWR_VR"
BOM_COST"PROC_SOCKET "
CDS_LIB"mstr_symbols"
VOLTAGE"1.2V"
BODY_TYPE"PLUMBING"
HDL_POWER"PVDDQ_ABC";
"G\NAC"14;
%"GND"
"1","(-1825,-1050)","0","mstr_symbols","I251";
;
BOM_COST"PROC_VRD_VCCIN_CPU0"
ROOM"VDDQ_ABC_PWR_VR"
CDS_LIB"mstr_symbols"
VOLTAGE"0"
SIZE"1B"
BODY_TYPE"PLUMBING"
HDL_POWER"GND";
"A\NAC"15;
%"SHUNT"
"1","(125,1500)","0","mstr_misc","I259";
;
CDS_SEC"1"
CDS_LOCATION"SH4U1"
LOCATION"SH4U1"
PART_NUMBER"N_A"
PIN_SHORT"A:B"
PACK_TYPE"SH0201"
MATERIAL"EMPTY"
CDS_LIB"mstr_misc"
SEC"1"
SEC_TYPE"SH0201";
"A"
$PN"1"29;
"B"
$PN"2"22;
%"SHUNT"
"1","(150,1950)","0","mstr_misc","I260";
;
CDS_SEC"1"
CDS_LOCATION"SH4U2"
LOCATION"SH4U2"
PART_NUMBER"N_A"
PIN_SHORT"A:B"
PACK_TYPE"SH0201"
MATERIAL"EMPTY"
CDS_LIB"mstr_misc"
SEC"1"
SEC_TYPE"SH0201";
"A"
$PN"1"28;
"B"
$PN"2"23;
%"IND-100NH-35-GP"
"1","(-200,925)","1","w_hdl","I261";
;
CDS_SEC"1"
CDS_LOCATION"L7F2"
TYPE"IRMS=29A@DELTA_T<45C"
PACK_SIZE"DCR=0.16MOHM"
RATED"ISAT=16A@25C"
ATTRIBUTE"100NH"
VALUE"IND-100NH-35-GP"
LOCATION"L7F2"
PACK_TYPE"DISCRET-G8"
SEC"1"
SEC_TYPE"DISCRET-G8"
PART_NUMBER"068.1011N.M001"
CDS_LIB"w_hdl"
CDS_LMAN_SYM_OUTLINE"-75,100,75,-100";
"F"
$PN"2"3;
"S"
$PN"1"5;
%"PVDDQ_ABC"
"1","(1025,3125)","0","mstr_symbols","I264";
;
CDS_LIB"mstr_symbols"
VOLTAGE"1.2V"
BOM_COST"MEM_VRD_PVDDQ_CD"
ROOM"VDDQ_ABC_PWR_VR"
BODY_TYPE"PLUMBING"
HDL_POWER"PVDDQ_ABC";
"G\NAC"16;
%"GND"
"1","(1025,2525)","0","mstr_symbols","I267";
;
VOLTAGE"0"
SIZE"1B"
CDS_LIB"mstr_symbols"
BODY_TYPE"PLUMBING"
HDL_POWER"GND";
"A\NAC"17;
%"CAP_A"
"1","(1000,1950)","0","dev_discrete","I269";
;
LOCATION"C5D58"
VALUE"22.0UF"
VOLTAGE"4V"
TOLERANCE"20%"
MATERIAL"X6S"
PART_NUMBER"E15431-004"
GROUP"PWR_MLCC_CAP"
PACK_TYPE"0603V"
CDS_LOCATION"C5D58"
BOM_COST"PROC_SOCKET"
CDS_LIB"dev_discrete"
CDS_SEC"1"
$SEC"1"
ROOM"PVCCIN_CPU0_DECAP_VR";
"B"
$PN"2"19;
"A"
$PN"1"18;
%"CAP_A"
"1","(1900,1950)","0","dev_discrete","I270";
;
TOLERANCE"20%"
VALUE"22.0UF"
LOCATION"C5D61"
GROUP"PWR_MLCC_CAP"
PART_NUMBER"E15431-004"
PACK_TYPE"0603V"
VOLTAGE"4V"
MATERIAL"X6S"
CDS_LOCATION"C5D61"
BOM_COST"PROC_SOCKET"
CDS_LIB"dev_discrete"
CDS_SEC"1"
$SEC"1"
ROOM"PVCCIN_CPU0_DECAP_VR";
"B"
$PN"2"19;
"A"
$PN"1"18;
%"CAP_A"
"1","(1300,1950)","0","dev_discrete","I271";
;
TOLERANCE"20%"
MATERIAL"X6S"
PART_NUMBER"E15431-004"
PACK_TYPE"0603V"
LOCATION"C5D59"
VALUE"22.0UF"
VOLTAGE"4V"
GROUP"PWR_MLCC_CAP"
ROOM"PVCCIN_CPU0_DECAP_VR"
$SEC"1"
CDS_SEC"1"
CDS_LIB"dev_discrete"
BOM_COST"PROC_SOCKET"
CDS_LOCATION"C5D59";
"B"
$PN"2"19;
"A"
$PN"1"18;
%"CAP_A"
"1","(1600,1950)","0","dev_discrete","I272";
;
GROUP"PWR_MLCC_CAP"
MATERIAL"X6S"
VOLTAGE"4V"
PART_NUMBER"E15431-004"
PACK_TYPE"0603V"
TOLERANCE"20%"
LOCATION"C5D60"
VALUE"22.0UF"
ROOM"PVCCIN_CPU0_DECAP_VR"
$SEC"1"
CDS_SEC"1"
CDS_LIB"dev_discrete"
BOM_COST"PROC_SOCKET"
CDS_LOCATION"C5D60";
"B"
$PN"2"19;
"A"
$PN"1"18;
%"PVDDQ_ABC"
"1","(1000,2200)","0","mstr_symbols","I273";
;
VOLTAGE"1.2V"
CDS_LIB"mstr_symbols"
BOM_COST"MEM_VRD_PVDDQ_CD"
ROOM"VDDQ_ABC_PWR_VR"
BODY_TYPE"PLUMBING"
HDL_POWER"PVDDQ_ABC";
"G\NAC"18;
%"GND"
"1","(1900,1600)","0","mstr_symbols","I274";
;
CDS_LIB"mstr_symbols"
SIZE"1B"
VOLTAGE"0"
BODY_TYPE"PLUMBING"
HDL_POWER"GND";
"A\NAC"19;
%"GND"
"1","(2000,2600)","0","mstr_symbols","I277";
;
CDS_LIB"mstr_symbols"
SIZE"1B"
VOLTAGE"0"
BODY_TYPE"PLUMBING"
HDL_POWER"GND";
"A\NAC"20;
%"PVDDQ_ABC"
"1","(2000,3150)","0","mstr_symbols","I278";
;
CDS_LIB"mstr_symbols"
VOLTAGE"1.2V"
BOM_COST"MEM_VRD_PVDDQ_CD"
ROOM"VDDQ_ABC_PWR_VR"
BODY_TYPE"PLUMBING"
HDL_POWER"PVDDQ_ABC";
"G\NAC"21;
%"CAP_A"
"1","(-900,2850)","0","dev_discrete","I279";
;
VALUE"22.0UF"
VOLTAGE"4V"
TOLERANCE"20%"
PACK_TYPE"0603V"
LOCATION"C5D54"
MATERIAL"X6S"
PART_NUMBER"E15431-004"
GROUP"PWR_MLCC_CAP"
CDS_LOCATION"C5D54"
BOM_COST"PROC_SOCKET"
CDS_LIB"dev_discrete"
CDS_SEC"1"
$SEC"1"
ROOM"PVCCIN_CPU0_DECAP_VR";
"B"
$PN"2"6;
"A"
$PN"1"10;
%"CAP_A"
"1","(-550,2850)","0","dev_discrete","I280";
;
TOLERANCE"20%"
VOLTAGE"4V"
MATERIAL"X6S"
LOCATION"C5D55"
VALUE"22.0UF"
GROUP"PWR_MLCC_CAP"
PART_NUMBER"E15431-004"
PACK_TYPE"0603V"
CDS_LOCATION"C5D55"
ROOM"PVCCIN_CPU0_DECAP_VR"
$SEC"1"
CDS_SEC"1"
CDS_LIB"dev_discrete"
BOM_COST"PROC_SOCKET";
"B"
$PN"2"6;
"A"
$PN"1"10;
%"CAP_A"
"1","(-200,2850)","0","dev_discrete","I281";
;
TOLERANCE"20%"
PART_NUMBER"E15431-004"
LOCATION"C5D56"
VOLTAGE"4V"
VALUE"22.0UF"
MATERIAL"X6S"
GROUP"PWR_MLCC_CAP"
PACK_TYPE"0603V"
CDS_LOCATION"C5D56"
ROOM"PVCCIN_CPU0_DECAP_VR"
$SEC"1"
CDS_SEC"1"
CDS_LIB"dev_discrete"
BOM_COST"PROC_SOCKET";
"B"
$PN"2"6;
"A"
$PN"1"10;
%"CAP_A"
"1","(150,2850)","0","dev_discrete","I282";
;
PART_NUMBER"E15431-004"
MATERIAL"X6S"
VALUE"22.0UF"
TOLERANCE"20%"
VOLTAGE"4V"
LOCATION"C5D57"
PACK_TYPE"0603V"
GROUP"PWR_MLCC_CAP"
CDS_LOCATION"C5D57"
BOM_COST"PROC_SOCKET"
CDS_LIB"dev_discrete"
CDS_SEC"1"
$SEC"1"
ROOM"PVCCIN_CPU0_DECAP_VR";
"B"
$PN"2"6;
"A"
$PN"1"10;
%"CAP_A"
"1","(-1825,50)","0","dev_discrete","I283";
;
BOM_SS"E15431-004"
VOLTAGE"4V"
PACK_TYPE"0603V"
TOLERANCE"20%"
MATERIAL"X5R"
PART_NUMBER"602433-106"
VALUE"47UF"
LOCATION"C5U2"
GROUP"PWR_MLCC_CAP"
SEC_TYPE"0603V"
SEC"1"
CDS_SEC"1"
CDS_LIB"dev_discrete"
CDS_LOCATION"C5U2";
"B"
$PN"2"13;
"A"
$PN"1"12;
%"CAP_A"
"1","(-1525,50)","0","dev_discrete","I284";
;
BOM_SS"E15431-004"
GROUP"PWR_MLCC_CAP"
LOCATION"C5U3"
MATERIAL"X5R"
PART_NUMBER"602433-106"
VOLTAGE"4V"
VALUE"47UF"
PACK_TYPE"0603V"
TOLERANCE"20%"
CDS_LOCATION"C5U3"
CDS_LIB"dev_discrete"
SEC"1"
SEC_TYPE"0603V"
CDS_SEC"1";
"B"
$PN"2"13;
"A"
$PN"1"12;
%"CAP_A"
"1","(-1225,50)","0","dev_discrete","I285";
;
BOM_SS"E15431-004"
MATERIAL"X5R"
PART_NUMBER"602433-106"
PACK_TYPE"0603V"
GROUP"PWR_MLCC_CAP"
VALUE"47UF"
TOLERANCE"20%"
VOLTAGE"4V"
LOCATION"C5U4"
CDS_LOCATION"C5U4"
CDS_SEC"1"
SEC_TYPE"0603V"
SEC"1"
CDS_LIB"dev_discrete";
"B"
$PN"2"13;
"A"
$PN"1"12;
%"CAP_A"
"1","(-950,50)","0","dev_discrete","I286";
;
BOM_SS"E15431-004"
LOCATION"C5U5"
VALUE"47UF"
VOLTAGE"4V"
GROUP"PWR_MLCC_CAP"
PACK_TYPE"0603V"
PART_NUMBER"602433-106"
TOLERANCE"20%"
MATERIAL"X5R"
CDS_LOCATION"C5U5"
CDS_LIB"dev_discrete"
SEC"1"
SEC_TYPE"0603V"
CDS_SEC"1";
"B"
$PN"2"13;
"A"
$PN"1"12;
%"CAP_A"
"1","(-675,50)","0","dev_discrete","I287";
;
BOM_SS"E15431-004"
PART_NUMBER"602433-106"
GROUP"PWR_MLCC_CAP"
TOLERANCE"20%"
PACK_TYPE"0603V"
MATERIAL"X5R"
VALUE"47UF"
VOLTAGE"4V"
LOCATION"C5U6"
CDS_LOCATION"C5U6"
CDS_SEC"1"
SEC_TYPE"0603V"
SEC"1"
CDS_LIB"dev_discrete";
"B"
$PN"2"13;
"A"
$PN"1"12;
%"CAP_A"
"1","(-375,50)","0","dev_discrete","I288";
;
MATERIAL"X5R"
GROUP"PWR_MLCC_CAP"
PART_NUMBER"602433-106"
TOLERANCE"20%"
LOCATION"C5U7"
VALUE"47UF"
VOLTAGE"4V"
PACK_TYPE"0603V"
BOM_SS"E15431-004"
CDS_LOCATION"C5U7"
CDS_LIB"dev_discrete"
SEC"1"
SEC_TYPE"0603V"
CDS_SEC"1";
"B"
$PN"2"13;
"A"
$PN"1"12;
%"CAP_A"
"1","(-75,50)","0","dev_discrete","I289";
;
BOM_SS"E15431-004"
MATERIAL"X5R"
TOLERANCE"20%"
VOLTAGE"4V"
VALUE"47UF"
LOCATION"C5U8"
GROUP"PWR_MLCC_CAP"
PACK_TYPE"0603V"
PART_NUMBER"602433-106"
CDS_LOCATION"C5U8"
CDS_SEC"1"
SEC_TYPE"0603V"
SEC"1"
CDS_LIB"dev_discrete";
"B"
$PN"2"13;
"A"
$PN"1"12;
%"CAP_A"
"1","(200,50)","0","dev_discrete","I290";
;
BOM_SS"E15431-004"
GROUP"PWR_MLCC_CAP"
TOLERANCE"20%"
MATERIAL"X5R"
LOCATION"C5U9"
VALUE"47UF"
VOLTAGE"4V"
PACK_TYPE"0603V"
PART_NUMBER"602433-106"
CDS_LOCATION"C5U9"
CDS_LIB"dev_discrete"
SEC"1"
SEC_TYPE"0603V"
CDS_SEC"1";
"B"
$PN"2"13;
"A"
$PN"1"12;
%"CAP_A"
"1","(525,50)","0","dev_discrete","I291";
;
BOM_SS"E15431-004"
GROUP"PWR_MLCC_CAP"
TOLERANCE"20%"
LOCATION"C5T12"
MATERIAL"X5R"
VOLTAGE"4V"
PACK_TYPE"0603V"
PART_NUMBER"602433-106"
VALUE"47UF"
CDS_LOCATION"C5T12"
CDS_LIB"dev_discrete"
SEC"1"
SEC_TYPE"0603V"
CDS_SEC"1";
"B"
$PN"2"13;
"A"
$PN"1"12;
%"CAP_A"
"1","(825,50)","0","dev_discrete","I292";
;
BOM_SS"E15431-004"
MATERIAL"X5R"
TOLERANCE"20%"
GROUP"PWR_MLCC_CAP"
LOCATION"C5T11"
VOLTAGE"4V"
VALUE"47UF"
PACK_TYPE"0603V"
PART_NUMBER"602433-106"
CDS_LOCATION"C5T11"
CDS_SEC"1"
SEC_TYPE"0603V"
SEC"1"
CDS_LIB"dev_discrete";
"B"
$PN"2"13;
"A"
$PN"1"12;
%"CAP_A"
"1","(1125,50)","0","dev_discrete","I293";
;
BOM_SS"E15431-004"
LOCATION"C5T10"
TOLERANCE"20%"
GROUP"PWR_MLCC_CAP"
VOLTAGE"4V"
VALUE"47UF"
MATERIAL"X5R"
PART_NUMBER"602433-106"
PACK_TYPE"0603V"
CDS_LOCATION"C5T10"
CDS_LIB"dev_discrete"
SEC"1"
SEC_TYPE"0603V"
CDS_SEC"1";
"B"
$PN"2"13;
"A"
$PN"1"12;
%"CAP_A"
"1","(1400,50)","0","dev_discrete","I294";
;
BOM_SS"E15431-004"
TOLERANCE"20%"
GROUP"PWR_MLCC_CAP"
PACK_TYPE"0603V"
PART_NUMBER"602433-106"
VOLTAGE"4V"
VALUE"47UF"
LOCATION"C5T9"
MATERIAL"X5R"
CDS_LOCATION"C5T9"
CDS_SEC"1"
SEC_TYPE"0603V"
SEC"1"
CDS_LIB"dev_discrete";
"B"
$PN"2"13;
"A"
$PN"1"12;
%"CAP_A"
"1","(1675,50)","0","dev_discrete","I295";
;
BOM_SS"E15431-004"
TOLERANCE"20%"
GROUP"PWR_MLCC_CAP"
PACK_TYPE"0603V"
VALUE"47UF"
VOLTAGE"4V"
LOCATION"C5T8"
PART_NUMBER"602433-106"
MATERIAL"X5R"
CDS_LOCATION"C5T8"
CDS_LIB"dev_discrete"
SEC"1"
SEC_TYPE"0603V"
CDS_SEC"1";
"B"
$PN"2"13;
"A"
$PN"1"12;
%"CAP_A"
"1","(1975,50)","0","dev_discrete","I296";
;
BOM_SS"E15431-004"
TOLERANCE"20%"
GROUP"PWR_MLCC_CAP"
LOCATION"C5T7"
VALUE"47UF"
VOLTAGE"4V"
MATERIAL"X5R"
PACK_TYPE"0603V"
PART_NUMBER"602433-106"
CDS_LOCATION"C5T7"
CDS_SEC"1"
SEC_TYPE"0603V"
SEC"1"
CDS_LIB"dev_discrete";
"B"
$PN"2"13;
"A"
$PN"1"12;
%"CAP_A"
"1","(2275,50)","0","dev_discrete","I297";
;
BOM_SS"E15431-004"
PACK_TYPE"0603V"
TOLERANCE"20%"
GROUP"PWR_MLCC_CAP"
LOCATION"C5T6"
VOLTAGE"4V"
VALUE"47UF"
MATERIAL"X5R"
PART_NUMBER"602433-106"
CDS_LOCATION"C5T6"
CDS_LIB"dev_discrete"
SEC"1"
SEC_TYPE"0603V"
CDS_SEC"1";
"B"
$PN"2"13;
"A"
$PN"1"12;
%"CAP_A"
"1","(2550,50)","0","dev_discrete","I298";
;
BOM_SS"E15431-004"
TOLERANCE"20%"
GROUP"PWR_MLCC_CAP"
PACK_TYPE"0603V"
PART_NUMBER"602433-106"
VOLTAGE"4V"
MATERIAL"X5R"
VALUE"47UF"
LOCATION"C5T5"
CDS_LOCATION"C5T5"
CDS_LIB"dev_discrete"
SEC"1"
SEC_TYPE"0603V"
CDS_SEC"1";
"B"
$PN"2"13;
"A"
$PN"1"12;
%"CAP_A"
"1","(-1825,-650)","0","dev_discrete","I299";
;
BOM_SS"E15431-004"
GROUP"PWR_MLCC_CAP"
TOLERANCE"20%"
PART_NUMBER"602433-106"
PACK_TYPE"0603V"
VOLTAGE"4V"
MATERIAL"X5R"
VALUE"47UF"
LOCATION"C5G11"
CDS_LOCATION"C5G11"
CDS_SEC"1"
SEC_TYPE"0603V"
SEC"1"
CDS_LIB"dev_discrete";
"B"
$PN"2"15;
"A"
$PN"1"14;
%"CAP_A"
"1","(-1525,-650)","0","dev_discrete","I300";
;
BOM_SS"E15431-004"
GROUP"PWR_MLCC_CAP"
TOLERANCE"20%"
VOLTAGE"4V"
MATERIAL"X5R"
PART_NUMBER"602433-106"
PACK_TYPE"0603V"
LOCATION"C5G12"
VALUE"47UF"
CDS_LOCATION"C5G12"
CDS_SEC"1"
SEC_TYPE"0603V"
SEC"1"
CDS_LIB"dev_discrete";
"B"
$PN"2"15;
"A"
$PN"1"14;
%"CAP_A"
"1","(-1225,-650)","0","dev_discrete","I301";
;
BOM_SS"E15431-004"
GROUP"PWR_MLCC_CAP"
TOLERANCE"20%"
PART_NUMBER"602433-106"
PACK_TYPE"0603V"
LOCATION"C5G2"
VALUE"47UF"
VOLTAGE"4V"
MATERIAL"X5R"
CDS_LOCATION"C5G2"
CDS_LIB"dev_discrete"
SEC"1"
SEC_TYPE"0603V"
CDS_SEC"1";
"B"
$PN"2"15;
"A"
$PN"1"14;
%"CAP_A"
"1","(-950,-650)","0","dev_discrete","I302";
;
BOM_SS"E15431-004"
PART_NUMBER"602433-106"
MATERIAL"X5R"
TOLERANCE"20%"
VALUE"47UF"
LOCATION"C5G4"
GROUP"PWR_MLCC_CAP"
PACK_TYPE"0603V"
VOLTAGE"4V"
CDS_LOCATION"C5G4"
CDS_SEC"1"
SEC_TYPE"0603V"
SEC"1"
CDS_LIB"dev_discrete";
"B"
$PN"2"15;
"A"
$PN"1"14;
%"CAP_A"
"1","(-675,-650)","0","dev_discrete","I303";
;
BOM_SS"E15431-004"
PART_NUMBER"602433-106"
GROUP"PWR_MLCC_CAP"
PACK_TYPE"0603V"
TOLERANCE"20%"
VALUE"47UF"
VOLTAGE"4V"
LOCATION"C5G13"
MATERIAL"X5R"
CDS_LOCATION"C5G13"
CDS_LIB"dev_discrete"
SEC"1"
SEC_TYPE"0603V"
CDS_SEC"1";
"B"
$PN"2"15;
"A"
$PN"1"14;
%"CAP_A"
"1","(-375,-650)","0","dev_discrete","I304";
;
BOM_SS"E15431-004"
MATERIAL"X5R"
TOLERANCE"20%"
PART_NUMBER"602433-106"
GROUP"PWR_MLCC_CAP"
LOCATION"C5G6"
VALUE"47UF"
PACK_TYPE"0603V"
VOLTAGE"4V"
CDS_LOCATION"C5G6"
CDS_SEC"1"
SEC_TYPE"0603V"
SEC"1"
CDS_LIB"dev_discrete";
"B"
$PN"2"15;
"A"
$PN"1"14;
%"CAP_A"
"1","(-75,-650)","0","dev_discrete","I305";
;
BOM_SS"E15431-004"
LOCATION"C5G5"
PART_NUMBER"602433-106"
VALUE"47UF"
GROUP"PWR_MLCC_CAP"
PACK_TYPE"0603V"
VOLTAGE"4V"
TOLERANCE"20%"
MATERIAL"X5R"
CDS_LOCATION"C5G5"
CDS_LIB"dev_discrete"
SEC"1"
SEC_TYPE"0603V"
CDS_SEC"1";
"B"
$PN"2"15;
"A"
$PN"1"14;
%"CAP_A"
"1","(200,-650)","0","dev_discrete","I306";
;
BOM_SS"E15431-004"
GROUP"PWR_MLCC_CAP"
VALUE"47UF"
TOLERANCE"20%"
VOLTAGE"4V"
PACK_TYPE"0603V"
MATERIAL"X5R"
LOCATION"C5G7"
PART_NUMBER"602433-106"
CDS_LOCATION"C5G7"
CDS_SEC"1"
SEC_TYPE"0603V"
SEC"1"
CDS_LIB"dev_discrete";
"B"
$PN"2"15;
"A"
$PN"1"14;
%"CAP_A"
"1","(525,-650)","0","dev_discrete","I307";
;
BOM_SS"E15431-004"
GROUP"PWR_MLCC_CAP"
LOCATION"C5G1"
PACK_TYPE"0603V"
MATERIAL"X5R"
PART_NUMBER"602433-106"
TOLERANCE"20%"
VOLTAGE"4V"
VALUE"47UF"
CDS_LOCATION"C5G1"
CDS_LIB"dev_discrete"
SEC"1"
SEC_TYPE"0603V"
CDS_SEC"1";
"B"
$PN"2"15;
"A"
$PN"1"14;
%"CAP_A"
"1","(825,-650)","0","dev_discrete","I308";
;
BOM_SS"E15431-004"
GROUP"PWR_MLCC_CAP"
LOCATION"C5G8"
VALUE"47UF"
PACK_TYPE"0603V"
MATERIAL"X5R"
PART_NUMBER"602433-106"
TOLERANCE"20%"
VOLTAGE"4V"
CDS_LOCATION"C5G8"
CDS_SEC"1"
SEC_TYPE"0603V"
SEC"1"
CDS_LIB"dev_discrete";
"B"
$PN"2"15;
"A"
$PN"1"14;
%"CAP_A"
"1","(1125,-650)","0","dev_discrete","I309";
;
BOM_SS"E15431-004"
LOCATION"C5G18"
VALUE"47UF"
VOLTAGE"4V"
TOLERANCE"20%"
MATERIAL"X5R"
PART_NUMBER"602433-106"
PACK_TYPE"0603V"
GROUP"PWR_MLCC_CAP"
CDS_LOCATION"C5G18"
CDS_LIB"dev_discrete"
SEC"1"
SEC_TYPE"0603V"
CDS_SEC"1";
"B"
$PN"2"15;
"A"
$PN"1"14;
%"CAP_A"
"1","(1400,-650)","0","dev_discrete","I310";
;
BOM_SS"E15431-004"
GROUP"PWR_MLCC_CAP"
MATERIAL"X5R"
TOLERANCE"20%"
LOCATION"C5G17"
PACK_TYPE"0603V"
PART_NUMBER"602433-106"
VALUE"47UF"
VOLTAGE"4V"
CDS_LOCATION"C5G17"
CDS_SEC"1"
SEC_TYPE"0603V"
SEC"1"
CDS_LIB"dev_discrete";
"B"
$PN"2"15;
"A"
$PN"1"14;
%"CAP_A"
"1","(1675,-650)","0","dev_discrete","I311";
;
BOM_SS"E15431-004"
PART_NUMBER"602433-106"
GROUP"PWR_MLCC_CAP"
TOLERANCE"20%"
MATERIAL"X5R"
PACK_TYPE"0603V"
VOLTAGE"4V"
VALUE"47UF"
LOCATION"C5G14"
CDS_LOCATION"C5G14"
CDS_LIB"dev_discrete"
SEC"1"
SEC_TYPE"0603V"
CDS_SEC"1";
"B"
$PN"2"15;
"A"
$PN"1"14;
%"CAP_A"
"1","(1975,-650)","0","dev_discrete","I312";
;
BOM_SS"E15431-004"
GROUP"PWR_MLCC_CAP"
VOLTAGE"4V"
PACK_TYPE"0603V"
MATERIAL"X5R"
TOLERANCE"20%"
PART_NUMBER"602433-106"
VALUE"47UF"
LOCATION"C5G16"
CDS_LOCATION"C5G16"
CDS_SEC"1"
SEC_TYPE"0603V"
SEC"1"
CDS_LIB"dev_discrete";
"B"
$PN"2"15;
"A"
$PN"1"14;
%"CAP_A"
"1","(2275,-650)","0","dev_discrete","I313";
;
BOM_SS"E15431-004"
GROUP"PWR_MLCC_CAP"
LOCATION"C5G15"
VALUE"47UF"
VOLTAGE"4V"
TOLERANCE"20%"
MATERIAL"X5R"
PART_NUMBER"602433-106"
PACK_TYPE"0603V"
CDS_LOCATION"C5G15"
CDS_LIB"dev_discrete"
SEC"1"
SEC_TYPE"0603V"
CDS_SEC"1";
"B"
$PN"2"15;
"A"
$PN"1"14;
%"CAP_A"
"1","(2550,-650)","0","dev_discrete","I314";
;
BOM_SS"E15431-004"
GROUP"PWR_MLCC_CAP"
TOLERANCE"20%"
PACK_TYPE"0603V"
VALUE"47UF"
VOLTAGE"4V"
LOCATION"C5G3"
MATERIAL"X5R"
PART_NUMBER"602433-106"
CDS_LOCATION"C5G3"
CDS_LIB"dev_discrete"
SEC"1"
SEC_TYPE"0603V"
CDS_SEC"1";
"B"
$PN"2"15;
"A"
$PN"1"14;
%"CAP"
"1","(4725,2850)","0","mstr_discrete","I316";
;
PACK_TYPE"0805"
LOCATION"C5U1"
VALUE"100UF"
VOLTAGE"4V"
PART_NUMBER"602433-112"
TOLERANCE"20%"
NEW_MATERIAL"X6S"
BOM_SS"NOPOP"
GROUP"PWR_MLCC_CAP"
NEW_PN"078.1071T.M002"
CDS_SEC"1"
CDS_LIB"mstr_discrete"
BOM_COST"MEM_VRD_PVDDQ_CD"
ROOM"VDDQ_ABC_PWR_VR"
SEC_TYPE"0805"
SEC"1"
MATERIAL"X5R"
CDS_LOCATION"C5U1";
"A"
$PN"1"26;
"B"
$PN"2"27;
%"CAP"
"1","(5075,2850)","0","mstr_discrete","I317";
;
VALUE"100UF"
TOLERANCE"20%"
LOCATION"C5U10"
VOLTAGE"4V"
PART_NUMBER"602433-112"
BOM_SS"NOPOP"
GROUP"PWR_MLCC_CAP"
PACK_TYPE"0805"
NEW_MATERIAL"X6S"
NEW_PN"078.1071T.M002"
CDS_SEC"1"
CDS_LIB"mstr_discrete"
BOM_COST"MEM_VRD_PVDDQ_CD"
ROOM"VDDQ_ABC_PWR_VR"
SEC_TYPE"0805"
SEC"1"
MATERIAL"X5R"
CDS_LOCATION"C5U10";
"A"
$PN"1"26;
"B"
$PN"2"27;
%"CAP"
"1","(3225,2850)","0","mstr_discrete","I318";
;
BOM_SS"NOPOP"
VALUE"100UF"
LOCATION"C5G9"
NEW_MATERIAL"X6S"
GROUP"PWR_MLCC_CAP"
NEW_PN"078.1071T.M002"
TOLERANCE"20%"
VOLTAGE"4V"
PART_NUMBER"602433-112"
PACK_TYPE"0805"
MATERIAL"X5R"
ROOM"VDDQ_ABC_PWR_VR"
BOM_COST"MEM_VRD_PVDDQ_CD"
SEC"1"
SEC_TYPE"0805"
CDS_LIB"mstr_discrete"
CDS_SEC"1"
CDS_LOCATION"C5G9";
"A"
$PN"1"26;
"B"
$PN"2"27;
%"CAP"
"1","(3625,2850)","0","mstr_discrete","I319";
;
PACK_TYPE"0805"
VOLTAGE"4V"
GROUP"PWR_MLCC_CAP"
LOCATION"C4T4"
VALUE"100UF"
BOM_SS"NOPOP"
NEW_MATERIAL"X6S"
NEW_PN"078.1071T.M002"
PART_NUMBER"602433-112"
TOLERANCE"20%"
CDS_SEC"1"
CDS_LIB"mstr_discrete"
BOM_COST"MEM_VRD_PVDDQ_CD"
ROOM"VDDQ_ABC_PWR_VR"
SEC_TYPE"0805"
SEC"1"
MATERIAL"X5R"
CDS_LOCATION"C4T4";
"A"
$PN"1"26;
"B"
$PN"2"27;
%"CAP"
"1","(3975,2850)","0","mstr_discrete","I320";
;
CDS_SEC"1"
CDS_LOCATION"C5U15"
LOCATION"C5U15"
TOLERANCE"20%"
VALUE"100UF"
VOLTAGE"4V"
BOM_SS"NOPOP"
PACK_TYPE"0805"
PART_NUMBER"602433-112"
GROUP"PWR_MLCC_CAP"
NEW_MATERIAL"X6S"
NEW_PN"078.1071T.M002"
SEC"1"
SEC_TYPE"0805"
CDS_LIB"mstr_discrete"
MATERIAL"X5R"
ROOM"VDDQ_ABC_PWR_VR"
BOM_COST"MEM_VRD_PVDDQ_CD";
"A"
$PN"1"26;
"B"
$PN"2"27;
%"CAP"
"1","(5475,2850)","0","mstr_discrete","I321";
;
TOLERANCE"20%"
VOLTAGE"4V"
PART_NUMBER"602433-112"
PACK_TYPE"0805"
VALUE"100UF"
LOCATION"C5U13"
NEW_MATERIAL"X6S"
BOM_SS"NOPOP"
GROUP"PWR_MLCC_CAP"
NEW_PN"078.1071T.M002"
CDS_SEC"1"
CDS_LIB"mstr_discrete"
BOM_COST"MEM_VRD_PVDDQ_CD"
ROOM"VDDQ_ABC_PWR_VR"
SEC_TYPE"0805"
SEC"1"
MATERIAL"X5R"
CDS_LOCATION"C5U13";
"A"
$PN"1"26;
"B"
$PN"2"27;
%"CAP"
"1","(4325,2850)","0","mstr_discrete","I322";
;
BOM_SS"NOPOP"
VOLTAGE"4V"
NEW_MATERIAL"X6S"
LOCATION"C5U14"
PACK_TYPE"0805"
PART_NUMBER"602433-112"
GROUP"PWR_MLCC_CAP"
TOLERANCE"20%"
VALUE"100UF"
NEW_PN"078.1071T.M002"
CDS_SEC"1"
CDS_LIB"mstr_discrete"
BOM_COST"MEM_VRD_PVDDQ_CD"
ROOM"VDDQ_ABC_PWR_VR"
SEC_TYPE"0805"
SEC"1"
MATERIAL"X5R"
CDS_LOCATION"C5U14";
"A"
$PN"1"26;
"B"
$PN"2"27;
%"CAP"
"1","(2000,2875)","0","mstr_discrete","I323";
;
NEW_PN"078.1071T.M002"
PACK_TYPE"0805"
NEW_MATERIAL"X6S"
GROUP"PWR_MLCC_CAP"
TOLERANCE"20%"
BOM_SS"NOPOP"
LOCATION"C5P41"
VOLTAGE"4V"
VALUE"100UF"
PART_NUMBER"602433-112"
CDS_SEC"1"
CDS_LIB"mstr_discrete"
BOM_COST"MEM_VRD_PVDDQ_CD"
ROOM"VDDQ_ABC_PWR_VR"
SEC_TYPE"0805"
SEC"1"
MATERIAL"X5R"
CDS_LOCATION"C5P41";
"A"
$PN"1"21;
"B"
$PN"2"20;
%"CAP"
"1","(700,2850)","0","mstr_discrete","I324";
;
PACK_TYPE"0805"
LOCATION"C5P44"
VALUE"100UF"
VOLTAGE"4V"
TOLERANCE"20%"
PART_NUMBER"602433-112"
BOM_SS"NOPOP"
NEW_MATERIAL"X6S"
NEW_PN"078.1071T.M002"
GROUP"PWR_MLCC_CAP"
MATERIAL"X5R"
SEC"1"
SEC_TYPE"0805"
ROOM"VDDQ_ABC_PWR_VR"
BOM_COST"MEM_VRD_PVDDQ_CD"
CDS_LIB"mstr_discrete"
CDS_SEC"1"
CDS_LOCATION"C5P44";
"A"
$PN"1"16;
"B"
$PN"2"17;
%"CAP"
"1","(1375,2850)","0","mstr_discrete","I325";
;
CDS_SEC"1"
$SEC"1"
CDS_LOCATION"C5P42"
NEW_PN"078.1071T.M002"
GROUP"PWR_MLCC_CAP"
BOM_SS"NOPOP"
LOCATION"C5P42"
VOLTAGE"4V"
VALUE"100UF"
PACK_TYPE"0805"
PART_NUMBER"602433-112"
TOLERANCE"20%"
NEW_MATERIAL"X6S"
CDS_LIB"mstr_discrete"
BOM_COST"MEM_VRD_PVDDQ_CD"
ROOM"VDDQ_ABC_PWR_VR"
MATERIAL"X5R";
"A"
$PN"1"16;
"B"
$PN"2"17;
%"CAP"
"1","(1025,2850)","0","mstr_discrete","I326";
;
CDS_SEC"1"
$SEC"1"
CDS_LOCATION"C5P43"
BOM_SS"NOPOP"
LOCATION"C5P43"
VALUE"100UF"
VOLTAGE"4V"
TOLERANCE"20%"
PACK_TYPE"0805"
PART_NUMBER"602433-112"
GROUP"PWR_MLCC_CAP"
NEW_MATERIAL"X6S"
NEW_PN"078.1071T.M002"
MATERIAL"X5R"
ROOM"VDDQ_ABC_PWR_VR"
BOM_COST"MEM_VRD_PVDDQ_CD"
CDS_LIB"mstr_discrete";
"A"
$PN"1"16;
"B"
$PN"2"17;
%"CAP"
"1","(-1400,2850)","0","mstr_discrete","I327";
;
LOCATION"C5P38"
VALUE"100UF"
VOLTAGE"4V"
PART_NUMBER"602433-112"
TOLERANCE"20%"
BOM_SS"NOPOP"
GROUP"PWR_MLCC_CAP"
NEW_MATERIAL"X6S"
PACK_TYPE"0805"
NEW_PN"078.1071T.M002"
MATERIAL"X5R"
SEC"1"
SEC_TYPE"0805"
ROOM"VDDQ_ABC_PWR_VR"
BOM_COST"MEM_VRD_PVDDQ_CD"
CDS_LIB"mstr_discrete"
CDS_SEC"1"
CDS_LOCATION"C5P38";
"A"
$PN"1"7;
"B"
$PN"2"11;
%"CAP"
"1","(-1750,2850)","0","mstr_discrete","I328";
;
CDS_SEC"1"
CDS_LOCATION"C5P39"
PART_NUMBER"602433-112"
PACK_TYPE"0805"
TOLERANCE"20%"
VOLTAGE"4V"
VALUE"100UF"
LOCATION"C5P39"
GROUP"PWR_MLCC_CAP"
BOM_SS"NOPOP"
NEW_MATERIAL"X6S"
NEW_PN"078.1071T.M002"
MATERIAL"X5R"
ROOM"VDDQ_ABC_PWR_VR"
BOM_COST"MEM_VRD_PVDDQ_CD"
CDS_LIB"mstr_discrete"
SEC"1"
SEC_TYPE"0805";
"A"
$PN"1"7;
"B"
$PN"2"11;
%"CAP"
"1","(2875,2850)","0","mstr_discrete","I329";
;
NEW_MATERIAL"X6S"
BOM_SS"NOPOP"
GROUP"PWR_MLCC_CAP"
PACK_TYPE"0805"
PART_NUMBER"602433-112"
TOLERANCE"20%"
VOLTAGE"4V"
VALUE"100UF"
LOCATION"C5G20"
NEW_PN"078.1071T.M002"
MATERIAL"X5R"
SEC"1"
SEC_TYPE"0805"
ROOM"VDDQ_ABC_PWR_VR"
BOM_COST"MEM_VRD_PVDDQ_CD"
CDS_LIB"mstr_discrete"
CDS_SEC"1"
CDS_LOCATION"C5G20";
"A"
$PN"1"26;
"B"
$PN"2"27;
%"RES"
"2","(4550,-400)","0","mstr_discrete","I58";
;
PACK_TYPE"0603"
MATERIAL"CHIP"
WATTAGE"1/10W"
TOLERANCE"1%"
VALUE"120.0"
LOCATION"R3U4"
PART_NUMBER"G22026-003"
CDS_SEC"1"
$SEC"1"
CDS_LOCATION"R3U4"
BOM_COST"MEM_VRD_PVPP_AB"
ROOM"VDDQ_ABC_PWR_VR"
CDS_LIB"mstr_discrete";
"A"
$PN"1"24;
"B"
$PN"2"25;
%"GND"
"1","(400,1275)","0","mstr_symbols","I65";
;
ROOM"VDDQ_ABC_PWR_VR"
BOM_COST"MEM_VRD_PVPP_AB"
SIZE"1B"
CDS_LIB"mstr_symbols"
VOLTAGE"0"
BODY_TYPE"PLUMBING"
HDL_POWER"GND";
"A\NAC"22;
%"PVDDQ_ABC"
"1","(425,2150)","0","mstr_symbols","I73";
;
BOM_COST"MEM_VRD_PVPP_AB"
CDS_LIB"mstr_symbols"
VOLTAGE"1.2V"
ROOM"VDDQ_ABC_PWR_VR"
BODY_TYPE"PLUMBING"
HDL_POWER"PVDDQ_ABC";
"G\NAC"23;
%"RES"
"2","(-250,1700)","0","mstr_discrete","I74";
;
CDS_SEC"1"
TOLERANCE"1%"
VALUE"100.0"
LOCATION"R4U6"
WATTAGE"1/16W"
MATERIAL"EMPTY"
PACK_TYPE"0402"
PART_NUMBER"G21796-017"
CDS_LIB"mstr_discrete"
SEC_TYPE"0402"
SEC"1"
CDS_LOCATION"R4U6"
ROOM"VDDQ_ABC_PWR_VR";
"A"
$PN"1"28;
"B"
$PN"2"29;
%"CAPP"
"1","(3350,-400)","0","mstr_discrete","I75";
;
CDS_SEC"1"
VOLTAGE"2.5V"
TOLERANCE"20%"
GROUP"PWR_BULK_CAP"
PART_NUMBER"699013-049"
PACK_TYPE"3018"
MATERIAL"ALUM"
VALUE"470UF"
LOCATION"C7G28"
SEC"1"
SEC_TYPE"3018"
ROOM"VDDQ_ABC_PWR_VR"
CDS_LOCATION"C7G28"
CDS_LIB"mstr_discrete";
"B"
$PN"2"25;
"A"
$PN"1"24;
%"CAPP"
"1","(3650,-400)","0","mstr_discrete","I76";
;
CDS_SEC"1"
GROUP"PWR_BULK_CAP"
VALUE"470UF"
TOLERANCE"20%"
VOLTAGE"2.5V"
PACK_TYPE"3018"
PART_NUMBER"699013-049"
MATERIAL"ALUM"
LOCATION"C3U1"
CDS_LIB"mstr_discrete"
SEC_TYPE"3018"
SEC"1"
CDS_LOCATION"C3U1"
ROOM"VDDQ_ABC_PWR_VR";
"B"
$PN"2"25;
"A"
$PN"1"24;
%"CAPP"
"1","(3950,-400)","0","mstr_discrete","I77";
;
CDS_SEC"1"
GROUP"PWR_BULK_CAP"
PART_NUMBER"699013-049"
LOCATION"C3U5"
VALUE"470UF"
TOLERANCE"20%"
VOLTAGE"2.5V"
MATERIAL"ALUM"
PACK_TYPE"3018"
SEC"1"
SEC_TYPE"3018"
CDS_LOCATION"C3U5"
ROOM"VDDQ_ABC_PWR_VR"
CDS_LIB"mstr_discrete";
"B"
$PN"2"25;
"A"
$PN"1"24;
%"CAPP"
"1","(4250,-400)","0","mstr_discrete","I78";
;
CDS_SEC"1"
PACK_TYPE"3018"
LOCATION"C3U8"
VALUE"470UF"
GROUP"PWR_BULK_CAP"
TOLERANCE"20%"
VOLTAGE"2.5V"
MATERIAL"ALUM"
PART_NUMBER"699013-049"
CDS_LIB"mstr_discrete"
CDS_LOCATION"C3U8"
ROOM"VDDQ_ABC_PWR_VR"
SEC_TYPE"3018"
SEC"1";
"B"
$PN"2"25;
"A"
$PN"1"24;
%"PVDDQ_ABC"
"1","(3350,-100)","0","mstr_symbols","I80";
;
HDL_POWER"PVDDQ_ABC"
BODY_TYPE"PLUMBING"
ROOM"VDDQ_ABC_PWR_VR"
VOLTAGE"1.2V"
CDS_LIB"mstr_symbols"
BOM_COST"MEM_VRD_PVPP_AB";
"G\NAC"24;
%"GND"
"1","(3350,-775)","0","mstr_symbols","I81";
;
HDL_POWER"GND"
BODY_TYPE"PLUMBING"
VOLTAGE"0"
SIZE"1B"
CDS_LIB"mstr_symbols"
BOM_COST"MEM_VRD_PVPP_AB"
ROOM"VDDQ_ABC_PWR_VR";
"A\NAC"25;
%"PVDDQ_ABC"
"1","(2875,3125)","0","mstr_symbols","I93";
;
BOM_COST"MEM_VRD_PVDDQ_CD"
CDS_LIB"mstr_symbols"
VOLTAGE"1.2V"
ROOM"VDDQ_ABC_PWR_VR"
BODY_TYPE"PLUMBING"
HDL_POWER"PVDDQ_ABC";
"G\NAC"26;
%"GND"
"1","(2875,2400)","0","mstr_symbols","I94";
;
SIZE"1B"
BOM_COST"MEM_VRD_PVDDQ_CD"
VOLTAGE"0"
CDS_LIB"mstr_symbols"
ROOM"VDDQ_ABC_PWR_VR"
BODY_TYPE"PLUMBING"
HDL_POWER"GND";
"A\NAC"27;
END.
